(kicad_pcb
	(version 20260206)
	(generator "pcbnew")
	(generator_version "10.0")
	(general
		(thickness 1.6)
		(legacy_teardrops no)
	)
	(paper "A4")
	(title_block
		(title "netronome-mezz — pcbd0082-001_rev01_jul9_a.brd")
		(comment 1 "Open CloudServer (Microsoft) / footprints 186-194 of 714")
	)
	(layers
		(0 "F.Cu" signal "TOP")
		(4 "In1.Cu" signal "02_GND")
		(6 "In2.Cu" signal "03_SIG")
		(8 "In3.Cu" signal "04_SIG")
		(10 "In4.Cu" signal "05_GND")
		(12 "In5.Cu" signal "06_PWR1")
		(14 "In6.Cu" signal "07_SIG")
		(16 "In7.Cu" signal "08_SIG")
		(18 "In8.Cu" signal "09_GND")
		(2 "B.Cu" signal "BOTTOM")
		(9 "F.Adhes" user "F.Adhesive")
		(11 "B.Adhes" user "B.Adhesive")
		(13 "F.Paste" user "Package Geometry/Pastemask Top")
		(15 "B.Paste" user "Package Geometry/Pastemask Bottom")
		(5 "F.SilkS" user "Ref Des/Silkscreen Top")
		(7 "B.SilkS" user "Ref Des/Silkscreen Bottom")
		(1 "F.Mask" user "Board Geometry/Soldermask Top")
		(3 "B.Mask" user "Board Geometry/Soldermask Bottom")
		(17 "Dwgs.User" user "User.Drawings")
		(19 "Cmts.User" user "User.Comments")
		(21 "Eco1.User" user "User.Eco1")
		(23 "Eco2.User" user "User.Eco2")
		(25 "Edge.Cuts" user "Board Geometry/Outline")
		(27 "Margin" user)
		(31 "F.CrtYd" user "Package Geometry/Place Bound Top")
		(29 "B.CrtYd" user "Package Geometry/Place Bound Bottom")
		(35 "F.Fab" user "Ref Des/Assembly Top")
		(33 "B.Fab" user "Ref Des/Assembly Bottom")
		(45 "User.4" user "COMPVAL_TYPE_BOTTOM")
	)
	(footprint ""
		(layer "F.Cu")
		(at 22.86 35.687 180)
		(property "Reference" "R61"
			(at 0 0 180)
			(layer "F.SilkS")
			(hide yes)
			(effects
				(font
					(size 1.27 1.27)
				)
			)
		)
		(property "Value" "4.75K"
			(at -0.148158 1.3462 270)
			(unlocked yes)
			(layer "F.Fab")
			(hide yes)
			(effects
				(font
					(size 1.27 0.9652)
					(thickness 0.000001)
				)
				(justify left)
			)
		)
		(property "Device Type" "REST4024"
			(at -0.148158 1.3462 270)
			(unlocked yes)
			(layer "F.Fab")
			(hide yes)
			(effects
				(font
					(size 1.27 0.9652)
					(thickness 0.000001)
				)
				(justify left)
			)
		)
		(duplicate_pad_numbers_are_jumpers no)
		(fp_poly
			(pts
				(xy 0.635 1.0668) (xy 0.635 -1.0668) (xy -0.635 -1.0668) (xy -0.635 1.0668)
			)
			(stroke
				(width 0)
				(type default)
			)
			(fill no)
			(layer "F.CrtYd")
		)
		(fp_line
			(start 0.254 0.508)
			(end -0.254 0.508)
			(stroke
				(width 0.0254)
				(type default)
			)
			(layer "F.Fab")
		)
		(fp_line
			(start 0.254 -0.508)
			(end 0.254 0.508)
			(stroke
				(width 0.0254)
				(type default)
			)
			(layer "F.Fab")
		)
		(fp_line
			(start -0.254 0.508)
			(end -0.254 -0.508)
			(stroke
				(width 0.0254)
				(type default)
			)
			(layer "F.Fab")
		)
		(fp_line
			(start -0.254 -0.508)
			(end 0.254 -0.508)
			(stroke
				(width 0.0254)
				(type default)
			)
			(layer "F.Fab")
		)
		(pad "1" smd rect
			(at 0 -0.4191 180)
			(size 0.508 0.5334)
			(layers "F.Cu" "F.Mask" "F.Paste")
			(net "EXT_3.3V")
		)
		(pad "2" smd rect
			(at 0 0.4191 180)
			(size 0.508 0.5334)
			(layers "F.Cu" "F.Mask" "F.Paste")
			(net "CPLD_PGRM_JTAG_TMS")
		)
		(zone
			(layer "F.Cu")
			(hatch none 0.5)
			(connect_pads
				(clearance 0)
			)
			(min_thickness 0.25)
			(keepout
				(tracks not_allowed)
				(vias allowed)
				(pads allowed)
				(copperpour not_allowed)
				(footprints allowed)
			)
			(placement
				(enabled no)
				(sheetname "")
			)
			(fill
				(thermal_gap 0.5)
				(thermal_bridge_width 0.5)
				(island_removal_mode 0)
			)
			(polygon
				(pts
					(xy 22.8346 35.7124) (xy 22.8346 35.6616) (xy 22.8854 35.6616) (xy 22.8854 35.7124)
				)
			)
		)
	)
	(footprint ""
		(layer "F.Cu")
		(at 75.819 4.318 -90)
		(property "Reference" "R288"
			(at -0.10033 4.064 0)
			(unlocked yes)
			(layer "F.SilkS")
			(effects
				(font
					(size 0.7874 0.5842)
					(thickness 0.127)
				)
				(justify left)
			)
		)
		(property "Value" "100"
			(at -0.148158 1.3462 0)
			(unlocked yes)
			(layer "F.Fab")
			(hide yes)
			(effects
				(font
					(size 1.27 0.9652)
					(thickness 0.000001)
				)
				(justify left)
			)
		)
		(property "Device Type" "REST4030"
			(at -0.148158 1.3462 0)
			(unlocked yes)
			(layer "F.Fab")
			(hide yes)
			(effects
				(font
					(size 1.27 0.9652)
					(thickness 0.000001)
				)
				(justify left)
			)
		)
		(duplicate_pad_numbers_are_jumpers no)
		(fp_poly
			(pts
				(xy 0.635 1.0668) (xy 0.635 -1.0668) (xy -0.635 -1.0668) (xy -0.635 1.0668)
			)
			(stroke
				(width 0)
				(type default)
			)
			(fill no)
			(layer "F.CrtYd")
		)
		(fp_line
			(start -0.254 0.508)
			(end -0.254 -0.508)
			(stroke
				(width 0.0254)
				(type default)
			)
			(layer "F.Fab")
		)
		(fp_line
			(start 0.254 0.508)
			(end -0.254 0.508)
			(stroke
				(width 0.0254)
				(type default)
			)
			(layer "F.Fab")
		)
		(fp_line
			(start -0.254 -0.508)
			(end 0.254 -0.508)
			(stroke
				(width 0.0254)
				(type default)
			)
			(layer "F.Fab")
		)
		(fp_line
			(start 0.254 -0.508)
			(end 0.254 0.508)
			(stroke
				(width 0.0254)
				(type default)
			)
			(layer "F.Fab")
		)
		(pad "1" smd rect
			(at 0 -0.4191 270)
			(size 0.508 0.5334)
			(layers "F.Cu" "F.Mask" "F.Paste")
			(net "DDR0_32A_VREF0B")
		)
		(pad "2" smd rect
			(at 0 0.4191 270)
			(size 0.508 0.5334)
			(layers "F.Cu" "F.Mask" "F.Paste")
			(net "DDR_VDDQ")
		)
		(zone
			(layer "F.Cu")
			(hatch none 0.5)
			(connect_pads
				(clearance 0)
			)
			(min_thickness 0.25)
			(keepout
				(tracks not_allowed)
				(vias allowed)
				(pads allowed)
				(copperpour not_allowed)
				(footprints allowed)
			)
			(placement
				(enabled no)
				(sheetname "")
			)
			(fill
				(thermal_gap 0.5)
				(thermal_bridge_width 0.5)
				(island_removal_mode 0)
			)
			(polygon
				(pts
					(xy 75.8444 4.3434) (xy 75.7936 4.3434) (xy 75.7936 4.2926) (xy 75.8444 4.2926)
				)
			)
		)
	)
	(footprint ""
		(layer "F.Cu")
		(at 49.403 46.482)
		(property "Reference" "TP63"
			(at -5.715 -0.10033 0)
			(unlocked yes)
			(layer "F.SilkS")
			(effects
				(font
					(size 0.7874 0.5842)
					(thickness 0.127)
				)
				(justify left)
			)
		)
		(property "Value" "*"
			(at -0.4826 -0.14732 0)
			(unlocked yes)
			(layer "F.Fab")
			(hide yes)
			(effects
				(font
					(size 1.27 0.9652)
					(thickness 0.000001)
				)
				(justify left)
			)
		)
		(property "Device Type" "TP_SMALL"
			(at -0.4826 -0.14732 0)
			(unlocked yes)
			(layer "F.Fab")
			(hide yes)
			(effects
				(font
					(size 1.27 0.9652)
					(thickness 0.000001)
				)
				(justify left)
			)
		)
		(duplicate_pad_numbers_are_jumpers no)
		(fp_line
			(start -0.8636 -0.8636)
			(end -0.8636 0.8636)
			(stroke
				(width 0.1524)
				(type default)
			)
			(layer "F.SilkS")
		)
		(fp_line
			(start -0.8636 0.8636)
			(end 0.8636 0.8636)
			(stroke
				(width 0.1524)
				(type default)
			)
			(layer "F.SilkS")
		)
		(fp_line
			(start 0.8636 -0.8636)
			(end -0.8636 -0.8636)
			(stroke
				(width 0.1524)
				(type default)
			)
			(layer "F.SilkS")
		)
		(fp_line
			(start 0.8636 0.8636)
			(end 0.8636 -0.8636)
			(stroke
				(width 0.1524)
				(type default)
			)
			(layer "F.SilkS")
		)
		(fp_poly
			(pts
				(xy -0.635 -0.635) (xy -0.635 0.635) (xy 0.635 0.635) (xy 0.635 -0.635)
			)
			(stroke
				(width 0)
				(type default)
			)
			(fill no)
			(layer "F.CrtYd")
		)
		(pad "1" smd rect
			(at 0 0)
			(size 1.27 1.27)
			(layers "F.Cu" "F.Mask" "F.Paste")
			(net "EXT_3.3V_PGOOD")
		)
	)
	(footprint ""
		(layer "F.Cu")
		(at 78.3082 22.987 180)
		(property "Reference" "R354"
			(at 0 0 180)
			(layer "F.SilkS")
			(hide yes)
			(effects
				(font
					(size 1.27 1.27)
				)
			)
		)
		(property "Value" "39.0"
			(at -0.148158 1.3462 270)
			(unlocked yes)
			(layer "F.Fab")
			(hide yes)
			(effects
				(font
					(size 1.27 0.9652)
					(thickness 0.000001)
				)
				(justify left)
			)
		)
		(property "Device Type" "REST0108"
			(at -0.148158 1.3462 270)
			(unlocked yes)
			(layer "F.Fab")
			(hide yes)
			(effects
				(font
					(size 1.27 0.9652)
					(thickness 0.000001)
				)
				(justify left)
			)
		)
		(duplicate_pad_numbers_are_jumpers no)
		(fp_poly
			(pts
				(xy 0.635 1.0668) (xy 0.635 -1.0668) (xy -0.635 -1.0668) (xy -0.635 1.0668)
			)
			(stroke
				(width 0)
				(type default)
			)
			(fill no)
			(layer "F.CrtYd")
		)
		(fp_line
			(start 0.254 0.508)
			(end -0.254 0.508)
			(stroke
				(width 0.0254)
				(type default)
			)
			(layer "F.Fab")
		)
		(fp_line
			(start 0.254 -0.508)
			(end 0.254 0.508)
			(stroke
				(width 0.0254)
				(type default)
			)
			(layer "F.Fab")
		)
		(fp_line
			(start -0.254 0.508)
			(end -0.254 -0.508)
			(stroke
				(width 0.0254)
				(type default)
			)
			(layer "F.Fab")
		)
		(fp_line
			(start -0.254 -0.508)
			(end 0.254 -0.508)
			(stroke
				(width 0.0254)
				(type default)
			)
			(layer "F.Fab")
		)
		(pad "1" smd rect
			(at 0 -0.4191 180)
			(size 0.508 0.5334)
			(layers "F.Cu" "F.Mask" "F.Paste")
			(net "DDR0_32A_ODT0")
		)
		(pad "2" smd rect
			(at 0 0.4191 180)
			(size 0.508 0.5334)
			(layers "F.Cu" "F.Mask" "F.Paste")
			(net "DDR_VTT")
		)
		(zone
			(layer "F.Cu")
			(hatch none 0.5)
			(connect_pads
				(clearance 0)
			)
			(min_thickness 0.25)
			(keepout
				(tracks not_allowed)
				(vias allowed)
				(pads allowed)
				(copperpour not_allowed)
				(footprints allowed)
			)
			(placement
				(enabled no)
				(sheetname "")
			)
			(fill
				(thermal_gap 0.5)
				(thermal_bridge_width 0.5)
				(island_removal_mode 0)
			)
			(polygon
				(pts
					(xy 78.2828 23.0124) (xy 78.2828 22.9616) (xy 78.3336 22.9616) (xy 78.3336 23.0124)
				)
			)
		)
	)
	(footprint ""
		(layer "F.Cu")
		(at 81.026 26.924)
		(property "Reference" "R222"
			(at 0 0 0)
			(layer "F.SilkS")
			(hide yes)
			(effects
				(font
					(size 1.27 1.27)
				)
			)
		)
		(property "Value" "39.0"
			(at -0.148158 1.3462 90)
			(unlocked yes)
			(layer "F.Fab")
			(hide yes)
			(effects
				(font
					(size 1.27 0.9652)
					(thickness 0.000001)
				)
				(justify left)
			)
		)
		(property "Device Type" "REST0108"
			(at -0.148158 1.3462 90)
			(unlocked yes)
			(layer "F.Fab")
			(hide yes)
			(effects
				(font
					(size 1.27 0.9652)
					(thickness 0.000001)
				)
				(justify left)
			)
		)
		(duplicate_pad_numbers_are_jumpers no)
		(fp_poly
			(pts
				(xy 0.635 1.0668) (xy 0.635 -1.0668) (xy -0.635 -1.0668) (xy -0.635 1.0668)
			)
			(stroke
				(width 0)
				(type default)
			)
			(fill no)
			(layer "F.CrtYd")
		)
		(fp_line
			(start -0.254 -0.508)
			(end 0.254 -0.508)
			(stroke
				(width 0.0254)
				(type default)
			)
			(layer "F.Fab")
		)
		(fp_line
			(start -0.254 0.508)
			(end -0.254 -0.508)
			(stroke
				(width 0.0254)
				(type default)
			)
			(layer "F.Fab")
		)
		(fp_line
			(start 0.254 -0.508)
			(end 0.254 0.508)
			(stroke
				(width 0.0254)
				(type default)
			)
			(layer "F.Fab")
		)
		(fp_line
			(start 0.254 0.508)
			(end -0.254 0.508)
			(stroke
				(width 0.0254)
				(type default)
			)
			(layer "F.Fab")
		)
		(pad "1" smd rect
			(at 0 -0.4191)
			(size 0.508 0.5334)
			(layers "F.Cu" "F.Mask" "F.Paste")
			(net "DDR0_32A_BA2")
		)
		(pad "2" smd rect
			(at 0 0.4191)
			(size 0.508 0.5334)
			(layers "F.Cu" "F.Mask" "F.Paste")
			(net "DDR_VTT")
		)
		(zone
			(layer "F.Cu")
			(hatch none 0.5)
			(connect_pads
				(clearance 0)
			)
			(min_thickness 0.25)
			(keepout
				(tracks not_allowed)
				(vias allowed)
				(pads allowed)
				(copperpour not_allowed)
				(footprints allowed)
			)
			(placement
				(enabled no)
				(sheetname "")
			)
			(fill
				(thermal_gap 0.5)
				(thermal_bridge_width 0.5)
				(island_removal_mode 0)
			)
			(polygon
				(pts
					(xy 81.0514 26.8986) (xy 81.0514 26.9494) (xy 81.0006 26.9494) (xy 81.0006 26.8986)
				)
			)
		)
	)
	(footprint ""
		(layer "F.Cu")
		(at 40.259 49.784)
		(property "Reference" "TP62"
			(at -1.524 -1.87833 0)
			(unlocked yes)
			(layer "F.SilkS")
			(effects
				(font
					(size 0.7874 0.5842)
					(thickness 0.127)
				)
				(justify left)
			)
		)
		(property "Value" "*"
			(at -0.4826 -0.14732 0)
			(unlocked yes)
			(layer "F.Fab")
			(hide yes)
			(effects
				(font
					(size 1.27 0.9652)
					(thickness 0.000001)
				)
				(justify left)
			)
		)
		(property "Device Type" "TP_SMALL"
			(at -0.4826 -0.14732 0)
			(unlocked yes)
			(layer "F.Fab")
			(hide yes)
			(effects
				(font
					(size 1.27 0.9652)
					(thickness 0.000001)
				)
				(justify left)
			)
		)
		(duplicate_pad_numbers_are_jumpers no)
		(fp_line
			(start -0.8636 -0.8636)
			(end -0.8636 0.8636)
			(stroke
				(width 0.1524)
				(type default)
			)
			(layer "F.SilkS")
		)
		(fp_line
			(start -0.8636 0.8636)
			(end 0.8636 0.8636)
			(stroke
				(width 0.1524)
				(type default)
			)
			(layer "F.SilkS")
		)
		(fp_line
			(start 0.8636 -0.8636)
			(end -0.8636 -0.8636)
			(stroke
				(width 0.1524)
				(type default)
			)
			(layer "F.SilkS")
		)
		(fp_line
			(start 0.8636 0.8636)
			(end 0.8636 -0.8636)
			(stroke
				(width 0.1524)
				(type default)
			)
			(layer "F.SilkS")
		)
		(fp_poly
			(pts
				(xy -0.635 -0.635) (xy -0.635 0.635) (xy 0.635 0.635) (xy 0.635 -0.635)
			)
			(stroke
				(width 0)
				(type default)
			)
			(fill no)
			(layer "F.CrtYd")
		)
		(pad "1" smd rect
			(at 0 0)
			(size 1.27 1.27)
			(layers "F.Cu" "F.Mask" "F.Paste")
			(net "EXT_12.0V_PGOOD")
		)
	)
	(footprint ""
		(layer "F.Cu")
		(at 63.6524 54.102)
		(property "Reference" "C183"
			(at -1.397 2.18567 0)
			(unlocked yes)
			(layer "F.SilkS")
			(effects
				(font
					(size 0.7874 0.5842)
					(thickness 0.127)
				)
				(justify left)
			)
		)
		(property "Value" ""
			(at 0 0 0)
			(layer "F.Fab")
			(effects
				(font
					(size 1.27 1.27)
				)
			)
		)
		(duplicate_pad_numbers_are_jumpers no)
		(fp_arc
			(start 0.379679 -0.337515)
			(mid 0.38034 -0.336767)
			(end 0.381 -0.336017)
			(stroke
				(width 0.2032)
				(type default)
			)
			(layer "F.SilkS")
		)
		(fp_arc
			(start 0.381 0.334264)
			(mid 0.380049 0.335357)
			(end 0.379095 0.336448)
			(stroke
				(width 0.2032)
				(type default)
			)
			(layer "F.SilkS")
		)
		(fp_circle
			(center 0 0)
			(end 0.508 0)
			(stroke
				(width 0.2032)
				(type default)
			)
			(fill no)
			(layer "F.SilkS")
		)
		(fp_poly
			(pts
				(xy -2.286 1.397) (xy -2.286 -1.778) (xy 2.286 -1.778) (xy 2.286 1.397)
			)
			(stroke
				(width 0)
				(type default)
			)
			(fill no)
			(layer "F.CrtYd")
		)
		(fp_line
			(start -1.524 -1.27)
			(end 1.524 -1.27)
			(stroke
				(width 0.0254)
				(type default)
			)
			(layer "F.Fab")
		)
		(fp_line
			(start -1.524 1.27)
			(end -1.524 -1.27)
			(stroke
				(width 0.0254)
				(type default)
			)
			(layer "F.Fab")
		)
		(fp_line
			(start 1.524 -1.27)
			(end 1.524 1.27)
			(stroke
				(width 0.0254)
				(type default)
			)
			(layer "F.Fab")
		)
		(fp_line
			(start 1.524 1.27)
			(end -1.524 1.27)
			(stroke
				(width 0.0254)
				(type default)
			)
			(layer "F.Fab")
		)
		(pad "1" smd rect
			(at -1.4224 0 90)
			(size 2.7432 1.3716)
			(layers "F.Cu" "F.Mask" "F.Paste")
			(net "EXT_12.0V")
		)
		(pad "2" smd rect
			(at 1.4224 0 90)
			(size 2.7432 1.3716)
			(layers "F.Cu" "F.Mask" "F.Paste")
			(net "GND")
		)
	)
	(footprint ""
		(layer "F.Cu")
		(at 25.908 38.608 90)
		(property "Reference" "C125"
			(at 0 0 90)
			(layer "F.SilkS")
			(hide yes)
			(effects
				(font
					(size 1.27 1.27)
				)
			)
		)
		(property "Value" "0.1UF"
			(at -0.091846 0.2921 180)
			(unlocked yes)
			(layer "F.Fab")
			(hide yes)
			(effects
				(font
					(size 0.7874 0.5842)
					(thickness 0.2032)
				)
				(justify left)
			)
		)
		(property "Device Type" "CAPC0073"
			(at -0.091846 0.2921 180)
			(unlocked yes)
			(layer "F.Fab")
			(hide yes)
			(effects
				(font
					(size 0.7874 0.5842)
					(thickness 0.2032)
				)
				(justify left)
			)
		)
		(duplicate_pad_numbers_are_jumpers no)
		(fp_poly
			(pts
				(xy 0.635 1.0668) (xy 0.635 -1.0668) (xy -0.635 -1.0668) (xy -0.635 1.0668)
			)
			(stroke
				(width 0)
				(type default)
			)
			(fill no)
			(layer "F.CrtYd")
		)
		(fp_line
			(start 0.254 -0.508)
			(end 0.254 0.508)
			(stroke
				(width 0.0254)
				(type default)
			)
			(layer "F.Fab")
		)
		(fp_line
			(start -0.254 -0.508)
			(end 0.254 -0.508)
			(stroke
				(width 0.0254)
				(type default)
			)
			(layer "F.Fab")
		)
		(fp_line
			(start 0.254 0.508)
			(end -0.254 0.508)
			(stroke
				(width 0.0254)
				(type default)
			)
			(layer "F.Fab")
		)
		(fp_line
			(start -0.254 0.508)
			(end -0.254 -0.508)
			(stroke
				(width 0.0254)
				(type default)
			)
			(layer "F.Fab")
		)
		(pad "1" smd rect
			(at 0 -0.4191 90)
			(size 0.508 0.5334)
			(layers "F.Cu" "F.Mask" "F.Paste")
			(net "NFP_VDD_CORE_SENSE_VSS")
		)
		(pad "2" smd rect
			(at 0 0.4191 90)
			(size 0.508 0.5334)
			(layers "F.Cu" "F.Mask" "F.Paste")
			(net "NFP_VDD_CORE_IMON")
		)
		(zone
			(layer "F.Cu")
			(hatch none 0.5)
			(connect_pads
				(clearance 0)
			)
			(min_thickness 0.25)
			(keepout
				(tracks not_allowed)
				(vias allowed)
				(pads allowed)
				(copperpour not_allowed)
				(footprints allowed)
			)
			(placement
				(enabled no)
				(sheetname "")
			)
			(fill
				(thermal_gap 0.5)
				(thermal_bridge_width 0.5)
				(island_removal_mode 0)
			)
			(polygon
				(pts
					(xy 25.8826 38.5826) (xy 25.9334 38.5826) (xy 25.9334 38.6334) (xy 25.8826 38.6334)
				)
			)
		)
	)
	(footprint ""
		(layer "F.Cu")
		(at 36.2712 40.767 90)
		(property "Reference" "R324"
			(at 0 0 90)
			(layer "F.SilkS")
			(hide yes)
			(effects
				(font
					(size 1.27 1.27)
				)
			)
		)
		(property "Value" "86.6K"
			(at -0.148158 1.3462 180)
			(unlocked yes)
			(layer "F.Fab")
			(hide yes)
			(effects
				(font
					(size 1.27 0.9652)
					(thickness 0.000001)
				)
				(justify left)
			)
		)
		(property "Device Type" "REST0029"
			(at -0.148158 1.3462 180)
			(unlocked yes)
			(layer "F.Fab")
			(hide yes)
			(effects
				(font
					(size 1.27 0.9652)
					(thickness 0.000001)
				)
				(justify left)
			)
		)
		(duplicate_pad_numbers_are_jumpers no)
		(fp_poly
			(pts
				(xy 0.635 1.0668) (xy 0.635 -1.0668) (xy -0.635 -1.0668) (xy -0.635 1.0668)
			)
			(stroke
				(width 0)
				(type default)
			)
			(fill no)
			(layer "F.CrtYd")
		)
		(fp_line
			(start 0.254 -0.508)
			(end 0.254 0.508)
			(stroke
				(width 0.0254)
				(type default)
			)
			(layer "F.Fab")
		)
		(fp_line
			(start -0.254 -0.508)
			(end 0.254 -0.508)
			(stroke
				(width 0.0254)
				(type default)
			)
			(layer "F.Fab")
		)
		(fp_line
			(start 0.254 0.508)
			(end -0.254 0.508)
			(stroke
				(width 0.0254)
				(type default)
			)
			(layer "F.Fab")
		)
		(fp_line
			(start -0.254 0.508)
			(end -0.254 -0.508)
			(stroke
				(width 0.0254)
				(type default)
			)
			(layer "F.Fab")
		)
		(pad "1" smd rect
			(at 0 -0.4191 90)
			(size 0.508 0.5334)
			(layers "F.Cu" "F.Mask" "F.Paste")
			(net "10N2528")
		)
		(pad "2" smd rect
			(at 0 0.4191 90)
			(size 0.508 0.5334)
			(layers "F.Cu" "F.Mask" "F.Paste")
			(net "NFP_VDD_CORE_ISEN2_P")
		)
		(zone
			(layer "F.Cu")
			(hatch none 0.5)
			(connect_pads
				(clearance 0)
			)
			(min_thickness 0.25)
			(keepout
				(tracks not_allowed)
				(vias allowed)
				(pads allowed)
				(copperpour not_allowed)
				(footprints allowed)
			)
			(placement
				(enabled no)
				(sheetname "")
			)
			(fill
				(thermal_gap 0.5)
				(thermal_bridge_width 0.5)
				(island_removal_mode 0)
			)
			(polygon
				(pts
					(xy 36.2458 40.7416) (xy 36.2966 40.7416) (xy 36.2966 40.7924) (xy 36.2458 40.7924)
				)
			)
		)
	)
)
